FILE_TYPE = MACRO_DRAWING;
SET COLOR_WIRE YELLOW;
SET COLOR_PROP ORANGE;
SET COLOR_DOT WHITE;
SET COLOR_ARC YELLOW;
SET COLOR_BODY GREEN;
SET COLOR_NOTE PURPLE;
SET PROP_DISPLAY VALUE;
SET PAGE_NUMBER P135;
FORCEADD QUANTA_TITLE_BLOCK_C..1
(-100 100);
FORCEPROP 1 LAST CUSTOM_TXT_CDS <NAME_2>
J 0
(-3275 150);
FORCEPROP 1 LAST CUSTOM_TXT_CDS <NAME_1>
J 0
(-3275 275);
FORCEPROP 1 LAST CUSTOM_TXT_CDS <Q_NUMBER>
J 0
(-1503 203);
DISPLAY 1.212766 (-1503 203);
FORCEPROP 1 LAST CUSTOM_TXT_CDS <Q_PROJ>
J 0
(-2482 202);
DISPLAY 1.212766 (-2482 202);
FORCEPROP 1 LAST CUSTOM_TXT_CDS <Q_REV>
J 0
(-284 203);
DISPLAY 1.212766 (-284 203);
FORCEPROP 1 LAST CUSTOM_TXT_CDS <CON_LAST_MODIFIED>
J 0
(-1985 115);
DISPLAY 0.978723 (-1985 115);
FORCEPROP 1 LAST CUSTOM_TXT_CDS <CON_PAGE_NUM> OF <CON_TOTAL_PAGES>
J 0
(-546 118);
DISPLAY 0.978723 (-546 118);
FORCEPROP 1 LAST Q_TITLE Blank
J 0
(-9350 175);
DISPLAY 2.446809 (-9350 175);
PAINT GREEN (-9350 175);
FORCEPROP 2 LAST PAGE_BORDER TRUE
J 0
(-7990 5350);
DISPLAY 0.638298 (-7990 5350);
PAINT PINK (-7990 5350);
DISPLAY INVISIBLE (-7990 5350);
FORCEPROP 1 LAST CDS_LMAN_SYM_OUTLINE -9475,6775,100,-125
J 0
(-100 100);
DISPLAY 0.468085 (-100 100);
PAINT GREEN (-100 100);
DISPLAY INVISIBLE (-100 100);
FORCEPROP 2 LAST CDS_LIB pure_quanta
J 0
(-100 100);
DISPLAY INVISIBLE (-100 100);
FORCEPROP 2 LAST CDS_XR_PAGE_TITLE CR-158 : @T6G_MB_LIB.T6G(SCH_1):PAGE158
J 0
(-7990 5350);
DISPLAY 0.638298 (-7990 5350);
PAINT PINK (-7990 5350);
DISPLAY INVISIBLE (-7990 5350);
FORCEPROP 2 LAST CUSTOM_TXT_CDS <XR_PAGE_TITLE>
J 0
(-7990 5350);
DISPLAY 0.638298 (-7990 5350);
PAINT PINK (-7990 5350);
DISPLAY INVISIBLE (-7990 5350);
FORCEPROP 1 LAST COMMENT_BODY TRUE
J 0
(-88 87);
DISPLAY 0.978723 (-88 87);
PAINT GREEN (-88 87);
DISPLAY INVISIBLE (-88 87);
FORCEPROP 1 LAST Q_DEPT BU9
J 1
(-3863 149);
DISPLAY 1.957447 (-3863 149);
PAINT GREEN (-3863 149);
DISPLAY INVISIBLE (-3863 149);
FORCEPROP 0 LAST CDS_CON_LAST_MODIFIED Thu Aug 24 10:14:44 2023
J 0
(-1985 115);
DISPLAY INVISIBLE (-1985 115);
QUIT
